# T6G (Grand Teton) — schematic netlist excerpt (pin names and nets, part order shuffled) for the footprints in the layout excerpt that follows; sources: Cadence DE-HDL packaged netlist, KiCad conversion of 04192023_DAF0TMB3IC0_F0TG_MB_C_brd_V02_OCP.brd

C2418  Q_CAP  22UF 4V 20% X6S  pkg C0402  page 74 : A = PVDDCR_SOC_P1 ; B = GND
C2322  Q_CAP  22UF 4V 20% X6S  pkg C0402  page 73 : A = PVDDCR_CPU0_P1 ; B = GND

(kicad_pcb
	(version 20260206)
	(generator "pcbnew")
	(generator_version "10.0")
	(general
		(thickness 1.6)
		(legacy_teardrops no)
	)
	(paper "A4")
	(title_block
		(title "04192023_DAF0TMB3IC0_F0TG_MB_C_brd_V02_OCP.brd")
		(comment 1 "Grand Teton / footprints 5072-5073 of 8354")
	)
	(layers
		(0 "F.Cu" signal "TOP")
		(4 "In1.Cu" signal "GND")
		(6 "In2.Cu" signal "IN1")
		(8 "In3.Cu" signal "GND1")
		(10 "In4.Cu" signal "IN2")
		(12 "In5.Cu" signal "GND2")
		(14 "In6.Cu" signal "IN3")
		(16 "In7.Cu" signal "GND3")
		(18 "In8.Cu" signal "VCC")
		(20 "In9.Cu" signal "VCC1")
		(22 "In10.Cu" signal "GND4")
		(24 "In11.Cu" signal "IN4")
		(26 "In12.Cu" signal "GND5")
		(28 "In13.Cu" signal "IN5")
		(30 "In14.Cu" signal "GND6")
		(32 "In15.Cu" signal "IN6")
		(34 "In16.Cu" signal "GND7")
		(2 "B.Cu" signal "BOTTOM")
		(9 "F.Adhes" user "F.Adhesive")
		(11 "B.Adhes" user "B.Adhesive")
		(13 "F.Paste" user "Package Geometry/Pastemask Top")
		(15 "B.Paste" user "Package Geometry/Pastemask Bottom")
		(5 "F.SilkS" user "Ref Des/Silkscreen Top")
		(7 "B.SilkS" user "Ref Des/Silkscreen Bottom")
		(1 "F.Mask" user "Board Geometry/Soldermask Top")
		(3 "B.Mask" user "Board Geometry/Soldermask Bottom")
		(17 "Dwgs.User" user "User.Drawings")
		(19 "Cmts.User" user "User.Comments")
		(21 "Eco1.User" user "User.Eco1")
		(23 "Eco2.User" user "User.Eco2")
		(25 "Edge.Cuts" user "Board Geometry/Outline")
		(27 "Margin" user)
		(31 "F.CrtYd" user "Package Geometry/Place Bound Top")
		(29 "B.CrtYd" user "Package Geometry/Place Bound Bottom")
		(35 "F.Fab" user "Ref Des/Assembly Top")
		(33 "B.Fab" user "Ref Des/Assembly Bottom")
	)
	(footprint ""
		(layer "B.Cu")
		(at 109.895386 -250.257564)
		(property "Reference" "C2322"
			(at 0 0 0)
			(layer "B.SilkS")
			(hide yes)
			(effects
				(font
					(size 1.27 1.27)
				)
				(justify mirror)
			)
		)
		(property "Value" ""
			(at 0 0 0)
			(layer "B.Fab")
			(effects
				(font
					(size 1.27 1.27)
				)
				(justify mirror)
			)
		)
		(duplicate_pad_numbers_are_jumpers no)
		(fp_line
			(start -0.7874 -0.4064)
			(end -0.7874 0.4064)
			(stroke
				(width 0.1524)
				(type default)
			)
			(layer "B.SilkS")
		)
		(fp_line
			(start -0.7874 0.4064)
			(end 0.7874 0.4064)
			(stroke
				(width 0.1524)
				(type default)
			)
			(layer "B.SilkS")
		)
		(fp_line
			(start 0.7874 -0.4064)
			(end -0.7874 -0.4064)
			(stroke
				(width 0.1524)
				(type default)
			)
			(layer "B.SilkS")
		)
		(fp_line
			(start 0.7874 0.4064)
			(end 0.7874 -0.4064)
			(stroke
				(width 0.1524)
				(type default)
			)
			(layer "B.SilkS")
		)
		(fp_line
			(start -0.67945 -0.3048)
			(end -0.67945 0.3048)
			(stroke
				(width 0.1)
				(type default)
			)
			(layer "B.Fab")
		)
		(fp_line
			(start -0.67945 0.3048)
			(end -0.120396 0.3048)
			(stroke
				(width 0.1)
				(type default)
			)
			(layer "B.Fab")
		)
		(fp_line
			(start -0.12065 -0.3048)
			(end -0.67945 -0.3048)
			(stroke
				(width 0.1)
				(type default)
			)
			(layer "B.Fab")
		)
		(fp_line
			(start -0.12065 -0.2794)
			(end -0.12065 -0.3048)
			(stroke
				(width 0.1)
				(type default)
			)
			(layer "B.Fab")
		)
		(fp_line
			(start -0.120396 0.2794)
			(end 0.12065 0.2794)
			(stroke
				(width 0.1)
				(type default)
			)
			(layer "B.Fab")
		)
		(fp_line
			(start -0.120396 0.3048)
			(end -0.120396 0.2794)
			(stroke
				(width 0.1)
				(type default)
			)
			(layer "B.Fab")
		)
		(fp_line
			(start 0.12065 -0.305054)
			(end 0.12065 -0.2794)
			(stroke
				(width 0.1)
				(type default)
			)
			(layer "B.Fab")
		)
		(fp_line
			(start 0.12065 -0.2794)
			(end -0.12065 -0.2794)
			(stroke
				(width 0.1)
				(type default)
			)
			(layer "B.Fab")
		)
		(fp_line
			(start 0.12065 0.2794)
			(end 0.12065 0.3048)
			(stroke
				(width 0.1)
				(type default)
			)
			(layer "B.Fab")
		)
		(fp_line
			(start 0.12065 0.3048)
			(end 0.67945 0.3048)
			(stroke
				(width 0.1)
				(type default)
			)
			(layer "B.Fab")
		)
		(fp_line
			(start 0.67945 -0.305054)
			(end 0.12065 -0.305054)
			(stroke
				(width 0.1)
				(type default)
			)
			(layer "B.Fab")
		)
		(fp_line
			(start 0.67945 0.3048)
			(end 0.67945 -0.305054)
			(stroke
				(width 0.1)
				(type default)
			)
			(layer "B.Fab")
		)
		(pad "1" smd circle
			(at 0.40005 0 180)
			(size 0 0)
			(layers "B.Cu" "B.Mask" "B.Paste")
			(net "PVDDCR_CPU0_P1")
		)
		(pad "2" smd circle
			(at -0.40005 0 180)
			(size 0 0)
			(layers "B.Cu" "B.Mask" "B.Paste")
			(net "GND")
		)
	)
	(footprint ""
		(layer "B.Cu")
		(at 115.275868 -256.012442 -90)
		(property "Reference" "C2418"
			(at 0 0 90)
			(layer "B.SilkS")
			(hide yes)
			(effects
				(font
					(size 1.27 1.27)
				)
				(justify mirror)
			)
		)
		(property "Value" ""
			(at 0 0 90)
			(layer "B.Fab")
			(effects
				(font
					(size 1.27 1.27)
				)
				(justify mirror)
			)
		)
		(duplicate_pad_numbers_are_jumpers no)
		(fp_line
			(start -0.7874 0.4064)
			(end 0.7874 0.4064)
			(stroke
				(width 0.1524)
				(type default)
			)
			(layer "B.SilkS")
		)
		(fp_line
			(start 0.7874 0.4064)
			(end 0.7874 -0.4064)
			(stroke
				(width 0.1524)
				(type default)
			)
			(layer "B.SilkS")
		)
		(fp_line
			(start -0.7874 -0.4064)
			(end -0.7874 0.4064)
			(stroke
				(width 0.1524)
				(type default)
			)
			(layer "B.SilkS")
		)
		(fp_line
			(start 0.7874 -0.4064)
			(end -0.7874 -0.4064)
			(stroke
				(width 0.1524)
				(type default)
			)
			(layer "B.SilkS")
		)
		(fp_line
			(start -0.67945 0.3048)
			(end -0.120396 0.3048)
			(stroke
				(width 0.1)
				(type default)
			)
			(layer "B.Fab")
		)
		(fp_line
			(start -0.120396 0.3048)
			(end -0.120396 0.2794)
			(stroke
				(width 0.1)
				(type default)
			)
			(layer "B.Fab")
		)
		(fp_line
			(start 0.12065 0.3048)
			(end 0.67945 0.3048)
			(stroke
				(width 0.1)
				(type default)
			)
			(layer "B.Fab")
		)
		(fp_line
			(start 0.67945 0.3048)
			(end 0.67945 -0.305054)
			(stroke
				(width 0.1)
				(type default)
			)
			(layer "B.Fab")
		)
		(fp_line
			(start -0.120396 0.2794)
			(end 0.12065 0.2794)
			(stroke
				(width 0.1)
				(type default)
			)
			(layer "B.Fab")
		)
		(fp_line
			(start 0.12065 0.2794)
			(end 0.12065 0.3048)
			(stroke
				(width 0.1)
				(type default)
			)
			(layer "B.Fab")
		)
		(fp_line
			(start -0.12065 -0.2794)
			(end -0.12065 -0.3048)
			(stroke
				(width 0.1)
				(type default)
			)
			(layer "B.Fab")
		)
		(fp_line
			(start 0.12065 -0.2794)
			(end -0.12065 -0.2794)
			(stroke
				(width 0.1)
				(type default)
			)
			(layer "B.Fab")
		)
		(fp_line
			(start -0.67945 -0.3048)
			(end -0.67945 0.3048)
			(stroke
				(width 0.1)
				(type default)
			)
			(layer "B.Fab")
		)
		(fp_line
			(start -0.12065 -0.3048)
			(end -0.67945 -0.3048)
			(stroke
				(width 0.1)
				(type default)
			)
			(layer "B.Fab")
		)
		(fp_line
			(start 0.12065 -0.305054)
			(end 0.12065 -0.2794)
			(stroke
				(width 0.1)
				(type default)
			)
			(layer "B.Fab")
		)
		(fp_line
			(start 0.67945 -0.305054)
			(end 0.12065 -0.305054)
			(stroke
				(width 0.1)
				(type default)
			)
			(layer "B.Fab")
		)
		(pad "1" smd circle
			(at 0.40005 0 90)
			(size 0 0)
			(layers "B.Cu" "B.Mask" "B.Paste")
			(net "PVDDCR_SOC_P1")
		)
		(pad "2" smd circle
			(at -0.40005 0 90)
			(size 0 0)
			(layers "B.Cu" "B.Mask" "B.Paste")
			(net "GND")
		)
	)
)
